(kicad_pcb
	(version 20241229)
	(generator "pcbnew")
	(generator_version "9.0")
	(general
		(thickness 1.6296)
		(legacy_teardrops no)
	)
	(paper "A3")
	(title_block
		(title "Thunderbolt to 10GbE adapter")
		(date "2026-04-21")
		(rev "1.1.0")
		(company "Antmicro Ltd")
		(comment 1 "www.antmicro.com")
		(comment 9 "footprint 288 of 703 (U14), pads 1-84 of 503")
	)
	(layers
		(0 "F.Cu" signal)
		(4 "In1.Cu" signal)
		(6 "In2.Cu" signal)
		(8 "In3.Cu" signal)
		(10 "In4.Cu" signal)
		(12 "In5.Cu" signal)
		(14 "In6.Cu" signal)
		(2 "B.Cu" signal)
		(9 "F.Adhes" user "F.Adhesive")
		(11 "B.Adhes" user "B.Adhesive")
		(13 "F.Paste" user)
		(15 "B.Paste" user)
		(5 "F.SilkS" user "F.Silkscreen")
		(7 "B.SilkS" user "B.Silkscreen")
		(1 "F.Mask" user)
		(3 "B.Mask" user)
		(17 "Dwgs.User" user "User.Drawings")
		(19 "Cmts.User" user "User.Comments")
		(21 "Eco1.User" user "User.Eco1")
		(23 "Eco2.User" user "User.Eco2")
		(25 "Edge.Cuts" user)
		(27 "Margin" user)
		(31 "F.CrtYd" user "F.Courtyard")
		(29 "B.CrtYd" user "B.Courtyard")
		(35 "F.Fab" user)
		(33 "B.Fab" user)
	)
	(footprint "antmicro-footprints:FCBGA-503_22x22mm_Layout21x24_P1mm"
		(layer "F.Cu")
		(at 151.005 81.499999 -90)
		(property "Reference" "U14"
			(at -11.499999 11.005 0)
			(layer "F.SilkS")
			(effects
				(font
					(size 0.7 0.7)
					(thickness 0.15)
				)
				(justify left bottom)
			)
		)
		(property "Value" "EZX710AT2_S_LMR5"
			(at -11.4 12.5 270)
			(layer "F.Fab")
			(effects
				(font
					(size 0.7 0.7)
					(thickness 0.15)
				)
				(justify left bottom)
			)
		)
		(property "Datasheet" "https://www.google.com/url?sa=t&source=web&rct=j&opi=89978449&url=https://cdrdv2-public.intel.com/596333/596333_X710-TM4_Datasheet_v_2_4.pdf&ved=2ahUKEwiSuv20_sCOAxXVCRAIHdxGO_UQFnoECBEQAQ&usg=AOvVaw1CjGyrGWE8ZvOdw4VBsY6U"
			(at 0 0 270)
			(layer "F.Fab")
			(effects
				(font
					(size 0.7 0.7)
					(thickness 0.15)
				)
				(justify left bottom)
			)
		)
		(property "Description" "Ethernet ICs Intel Ethernet Controller 10 Gigabit X7"
			(at 0 0 270)
			(layer "F.Fab")
			(effects
				(font
					(size 0.7 0.7)
					(thickness 0.15)
				)
				(justify left bottom)
			)
		)
		(property "MPN" "EZX710AT2 S LMR5"
			(at 0 0 270)
			(unlocked yes)
			(layer "F.Fab")
			(hide yes)
			(effects
				(font
					(size 1 1)
					(thickness 0.15)
				)
			)
		)
		(property "Manufacturer" "Intel"
			(at 0 0 270)
			(unlocked yes)
			(layer "F.Fab")
			(hide yes)
			(effects
				(font
					(size 1 1)
					(thickness 0.15)
				)
			)
		)
		(property "Author" "Antmicro"
			(at 0 0 270)
			(unlocked yes)
			(layer "F.Fab")
			(hide yes)
			(effects
				(font
					(size 1 1)
					(thickness 0.15)
				)
			)
		)
		(property "License" "Apache-2.0"
			(at 0 0 270)
			(unlocked yes)
			(layer "F.Fab")
			(hide yes)
			(effects
				(font
					(size 1 1)
					(thickness 0.15)
				)
			)
		)
		(sheetname "/X710-AT2 power/")
		(sheetfile "x710-at2-power.kicad_sch")
		(attr smd)
		(pad "A3" smd circle
			(at -9.25 -9.95 270)
			(size 0.5 0.5)
			(layers "F.Cu" "F.Mask" "F.Paste")
			(net 23 "GND")
			(pinfunction "VSSA")
			(pintype "power_in")
		)
		(pad "A5" smd circle
			(at -8.25 -9.95 270)
			(size 0.5 0.5)
			(layers "F.Cu" "F.Mask" "F.Paste")
			(net 512 "unconnected-(U14B-SER1_RX_N-PadA5)")
			(pinfunction "SER1_RX_N")
			(pintype "input+no_connect")
		)
		(pad "A7" smd circle
			(at -7.25 -9.95 270)
			(size 0.5 0.5)
			(layers "F.Cu" "F.Mask" "F.Paste")
			(net 23 "GND")
			(pinfunction "VSSA")
			(pintype "passive")
		)
		(pad "A9" smd circle
			(at -6.25 -9.95 270)
			(size 0.5 0.5)
			(layers "F.Cu" "F.Mask" "F.Paste")
			(net 509 "unconnected-(U14B-SER1_TX_P-PadA9)")
			(pinfunction "SER1_TX_P")
			(pintype "output+no_connect")
		)
		(pad "A11" smd circle
			(at -5.25 -9.95 270)
			(size 0.5 0.5)
			(layers "F.Cu" "F.Mask" "F.Paste")
			(net 23 "GND")
			(pinfunction "VSSA")
			(pintype "passive")
		)
		(pad "A13" smd circle
			(at -4.25 -9.95 270)
			(size 0.5 0.5)
			(layers "F.Cu" "F.Mask" "F.Paste")
			(net 548 "unconnected-(U14B-SER0_RX_N-PadA13)")
			(pinfunction "SER0_RX_N")
			(pintype "input+no_connect")
		)
		(pad "A15" smd circle
			(at -3.25 -9.95 270)
			(size 0.5 0.5)
			(layers "F.Cu" "F.Mask" "F.Paste")
			(net 23 "GND")
			(pinfunction "VSSA")
			(pintype "passive")
		)
		(pad "A17" smd circle
			(at -2.25 -9.95 270)
			(size 0.5 0.5)
			(layers "F.Cu" "F.Mask" "F.Paste")
			(net 475 "unconnected-(U14B-SER0_TX_P-PadA17)")
			(pinfunction "SER0_TX_P")
			(pintype "output+no_connect")
		)
		(pad "A19" smd circle
			(at -1.25 -9.95 270)
			(size 0.5 0.5)
			(layers "F.Cu" "F.Mask" "F.Paste")
			(net 23 "GND")
			(pinfunction "VSSA")
			(pintype "passive")
		)
		(pad "A21" smd circle
			(at -0.25 -9.95 270)
			(size 0.5 0.5)
			(layers "F.Cu" "F.Mask" "F.Paste")
			(net 23 "GND")
			(pinfunction "AVSS")
			(pintype "power_in")
		)
		(pad "A23" smd circle
			(at 0.75 -9.95 270)
			(size 0.5 0.5)
			(layers "F.Cu" "F.Mask" "F.Paste")
			(net 52 "/2xRJ45/Ethernet_P1.D1+")
			(pinfunction "P1_A_P")
			(pintype "bidirectional")
		)
		(pad "A25" smd circle
			(at 1.75 -9.95 270)
			(size 0.5 0.5)
			(layers "F.Cu" "F.Mask" "F.Paste")
			(net 46 "/2xRJ45/Ethernet_P1.D2-")
			(pinfunction "P1_B_N")
			(pintype "bidirectional")
		)
		(pad "A27" smd circle
			(at 2.75 -9.95 270)
			(size 0.5 0.5)
			(layers "F.Cu" "F.Mask" "F.Paste")
			(net 48 "/2xRJ45/Ethernet_P1.D3+")
			(pinfunction "P1_C_P")
			(pintype "bidirectional")
		)
		(pad "A29" smd circle
			(at 3.75 -9.95 270)
			(size 0.5 0.5)
			(layers "F.Cu" "F.Mask" "F.Paste")
			(net 51 "/2xRJ45/Ethernet_P1.D4-")
			(pinfunction "P1_D_N")
			(pintype "bidirectional")
		)
		(pad "A31" smd circle
			(at 4.75 -9.95 270)
			(size 0.5 0.5)
			(layers "F.Cu" "F.Mask" "F.Paste")
			(net 23 "GND")
			(pinfunction "AVSS")
			(pintype "passive")
		)
		(pad "A33" smd circle
			(at 5.75 -9.95 270)
			(size 0.5 0.5)
			(layers "F.Cu" "F.Mask" "F.Paste")
			(net 41 "/2xRJ45/Ethernet_P0.D4+")
			(pinfunction "P0_D_P")
			(pintype "bidirectional")
		)
		(pad "A35" smd circle
			(at 6.75 -9.95 270)
			(size 0.5 0.5)
			(layers "F.Cu" "F.Mask" "F.Paste")
			(net 38 "/2xRJ45/Ethernet_P0.D3-")
			(pinfunction "P0_C_N")
			(pintype "bidirectional")
		)
		(pad "A37" smd circle
			(at 7.75 -9.95 270)
			(size 0.5 0.5)
			(layers "F.Cu" "F.Mask" "F.Paste")
			(net 39 "/2xRJ45/Ethernet_P0.D2+")
			(pinfunction "P0_B_P")
			(pintype "bidirectional")
		)
		(pad "A39" smd circle
			(at 8.75 -9.95 270)
			(size 0.5 0.5)
			(layers "F.Cu" "F.Mask" "F.Paste")
			(net 37 "/2xRJ45/Ethernet_P0.D1-")
			(pinfunction "P0_A_N")
			(pintype "bidirectional")
		)
		(pad "A41" smd circle
			(at 9.75 -9.95 270)
			(size 0.5 0.5)
			(layers "F.Cu" "F.Mask" "F.Paste")
			(net 504 "unconnected-(U14G-RSVDA41_NC-PadA41)")
			(pinfunction "RSVDA41_NC")
			(pintype "passive+no_connect")
		)
		(pad "AA1" smd circle
			(at -10.25 7.35 270)
			(size 0.5 0.5)
			(layers "F.Cu" "F.Mask" "F.Paste")
			(net 159 "/X710-AT2 PCIe/CLK+")
			(pinfunction "PE_CLK_P")
			(pintype "input")
		)
		(pad "AA3" smd circle
			(at -9.25 7.35 270)
			(size 0.5 0.5)
			(layers "F.Cu" "F.Mask" "F.Paste")
			(net 23 "GND")
			(pinfunction "VSSA")
			(pintype "passive")
		)
		(pad "AA5" smd circle
			(at -8.25 7.35 270)
			(size 0.5 0.5)
			(layers "F.Cu" "F.Mask" "F.Paste")
			(net 314 "/TB Controller/PCIex4.RX0+")
			(pinfunction "PER_0_P")
			(pintype "input")
		)
		(pad "AA7" smd circle
			(at -7.25 7.35 270)
			(size 0.5 0.5)
			(layers "F.Cu" "F.Mask" "F.Paste")
			(net 322 "/TB Controller/PCIex4.RX0-")
			(pinfunction "PER_0_N")
			(pintype "input")
		)
		(pad "AA9" smd circle
			(at -6.25 7.35 270)
			(size 0.5 0.5)
			(layers "F.Cu" "F.Mask" "F.Paste")
			(net 23 "GND")
			(pinfunction "VSSA")
			(pintype "passive")
		)
		(pad "AA11" smd circle
			(at -5.25 7.35 270)
			(size 0.5 0.5)
			(layers "F.Cu" "F.Mask" "F.Paste")
			(net 23 "GND")
			(pinfunction "VSSA")
			(pintype "passive")
		)
		(pad "AA13" smd circle
			(at -4.25 7.35 270)
			(size 0.5 0.5)
			(layers "F.Cu" "F.Mask" "F.Paste")
			(net 23 "GND")
			(pinfunction "VSSA")
			(pintype "passive")
		)
		(pad "AA15" smd circle
			(at -3.25 7.35 270)
			(size 0.5 0.5)
			(layers "F.Cu" "F.Mask" "F.Paste")
			(net 23 "GND")
			(pinfunction "VSSA")
			(pintype "passive")
		)
		(pad "AA17" smd circle
			(at -2.25 7.35 270)
			(size 0.5 0.5)
			(layers "F.Cu" "F.Mask" "F.Paste")
			(net 23 "GND")
			(pinfunction "VSSA")
			(pintype "passive")
		)
		(pad "AA19" smd circle
			(at -1.25 7.35 270)
			(size 0.5 0.5)
			(layers "F.Cu" "F.Mask" "F.Paste")
			(net 23 "GND")
			(pinfunction "VSSA")
			(pintype "passive")
		)
		(pad "AA21" smd circle
			(at -0.25 7.35 270)
			(size 0.5 0.5)
			(layers "F.Cu" "F.Mask" "F.Paste")
			(net 23 "GND")
			(pinfunction "VSSA")
			(pintype "passive")
		)
		(pad "AA23" smd circle
			(at 0.75 7.35 270)
			(size 0.5 0.5)
			(layers "F.Cu" "F.Mask" "F.Paste")
			(net 23 "GND")
			(pinfunction "VSSA")
			(pintype "passive")
		)
		(pad "AA25" smd circle
			(at 1.75 7.35 270)
			(size 0.5 0.5)
			(layers "F.Cu" "F.Mask" "F.Paste")
			(net 23 "GND")
			(pinfunction "VSSA")
			(pintype "passive")
		)
		(pad "AA27" smd circle
			(at 2.75 7.35 270)
			(size 0.5 0.5)
			(layers "F.Cu" "F.Mask" "F.Paste")
			(net 448 "unconnected-(U14A-PER_4_P-PadAA27)")
			(pinfunction "PER_4_P")
			(pintype "input+no_connect")
		)
		(pad "AA29" smd circle
			(at 3.75 7.35 270)
			(size 0.5 0.5)
			(layers "F.Cu" "F.Mask" "F.Paste")
			(net 23 "GND")
			(pinfunction "VSSA")
			(pintype "passive")
		)
		(pad "AA31" smd circle
			(at 4.75 7.35 270)
			(size 0.5 0.5)
			(layers "F.Cu" "F.Mask" "F.Paste")
			(net 463 "unconnected-(U14A-PER_5_N-PadAA31)")
			(pinfunction "PER_5_N")
			(pintype "input+no_connect")
		)
		(pad "AA33" smd circle
			(at 5.75 7.35 270)
			(size 0.5 0.5)
			(layers "F.Cu" "F.Mask" "F.Paste")
			(net 23 "GND")
			(pinfunction "VSSA")
			(pintype "passive")
		)
		(pad "AA35" smd circle
			(at 6.75 7.35 270)
			(size 0.5 0.5)
			(layers "F.Cu" "F.Mask" "F.Paste")
			(net 450 "unconnected-(U14A-PER_6_N-PadAA35)")
			(pinfunction "PER_6_N")
			(pintype "input+no_connect")
		)
		(pad "AA37" smd circle
			(at 7.75 7.35 270)
			(size 0.5 0.5)
			(layers "F.Cu" "F.Mask" "F.Paste")
			(net 23 "GND")
			(pinfunction "VSSA")
			(pintype "passive")
		)
		(pad "AA39" smd circle
			(at 8.75 7.35 270)
			(size 0.5 0.5)
			(layers "F.Cu" "F.Mask" "F.Paste")
			(net 490 "unconnected-(U14A-PER_7_N-PadAA39)")
			(pinfunction "PER_7_N")
			(pintype "input+no_connect")
		)
		(pad "AA41" smd circle
			(at 9.75 7.35 270)
			(size 0.5 0.5)
			(layers "F.Cu" "F.Mask" "F.Paste")
			(net 23 "GND")
			(pinfunction "VSSA")
			(pintype "passive")
		)
		(pad "AB2" smd circle
			(at -9.75 8.215 270)
			(size 0.5 0.5)
			(layers "F.Cu" "F.Mask" "F.Paste")
			(net 160 "/X710-AT2 PCIe/CLK-")
			(pinfunction "PE_CLK_N")
			(pintype "input")
		)
		(pad "AB4" smd circle
			(at -8.75 8.215 270)
			(size 0.5 0.5)
			(layers "F.Cu" "F.Mask" "F.Paste")
			(net 23 "GND")
			(pinfunction "VSSA")
			(pintype "passive")
		)
		(pad "AB6" smd circle
			(at -7.75 8.215 270)
			(size 0.5 0.5)
			(layers "F.Cu" "F.Mask" "F.Paste")
			(net 23 "GND")
			(pinfunction "VSSA")
			(pintype "passive")
		)
		(pad "AB8" smd circle
			(at -6.75 8.215 270)
			(size 0.5 0.5)
			(layers "F.Cu" "F.Mask" "F.Paste")
			(net 23 "GND")
			(pinfunction "VSSA")
			(pintype "passive")
		)
		(pad "AB10" smd circle
			(at -5.75 8.215 270)
			(size 0.5 0.5)
			(layers "F.Cu" "F.Mask" "F.Paste")
			(net 317 "/TB Controller/PCIex4.RX1+")
			(pinfunction "PER_1_P")
			(pintype "input")
		)
		(pad "AB12" smd circle
			(at -4.75 8.215 270)
			(size 0.5 0.5)
			(layers "F.Cu" "F.Mask" "F.Paste")
			(net 324 "/TB Controller/PCIex4.RX1-")
			(pinfunction "PER_1_N")
			(pintype "input")
		)
		(pad "AB14" smd circle
			(at -3.75 8.215 270)
			(size 0.5 0.5)
			(layers "F.Cu" "F.Mask" "F.Paste")
			(net 23 "GND")
			(pinfunction "VSSA")
			(pintype "passive")
		)
		(pad "AB16" smd circle
			(at -2.75 8.215 270)
			(size 0.5 0.5)
			(layers "F.Cu" "F.Mask" "F.Paste")
			(net 319 "/TB Controller/PCIex4.RX2+")
			(pinfunction "PER_2_P")
			(pintype "input")
		)
		(pad "AB18" smd circle
			(at -1.75 8.215 270)
			(size 0.5 0.5)
			(layers "F.Cu" "F.Mask" "F.Paste")
			(net 326 "/TB Controller/PCIex4.RX2-")
			(pinfunction "PER_2_N")
			(pintype "input")
		)
		(pad "AB20" smd circle
			(at -0.75 8.215 270)
			(size 0.5 0.5)
			(layers "F.Cu" "F.Mask" "F.Paste")
			(net 23 "GND")
			(pinfunction "VSSA")
			(pintype "passive")
		)
		(pad "AB22" smd circle
			(at 0.25 8.215 270)
			(size 0.5 0.5)
			(layers "F.Cu" "F.Mask" "F.Paste")
			(net 321 "/TB Controller/PCIex4.RX3+")
			(pinfunction "PER_3_P")
			(pintype "input")
		)
		(pad "AB24" smd circle
			(at 1.25 8.215 270)
			(size 0.5 0.5)
			(layers "F.Cu" "F.Mask" "F.Paste")
			(net 328 "/TB Controller/PCIex4.RX3-")
			(pinfunction "PER_3_N")
			(pintype "input")
		)
		(pad "AB26" smd circle
			(at 2.25 8.215 270)
			(size 0.5 0.5)
			(layers "F.Cu" "F.Mask" "F.Paste")
			(net 23 "GND")
			(pinfunction "VSSA")
			(pintype "passive")
		)
		(pad "AB28" smd circle
			(at 3.25 8.215 270)
			(size 0.5 0.5)
			(layers "F.Cu" "F.Mask" "F.Paste")
			(net 471 "unconnected-(U14A-PER_4_N-PadAB28)")
			(pinfunction "PER_4_N")
			(pintype "input+no_connect")
		)
		(pad "AB30" smd circle
			(at 4.25 8.215 270)
			(size 0.5 0.5)
			(layers "F.Cu" "F.Mask" "F.Paste")
			(net 23 "GND")
			(pinfunction "VSSA")
			(pintype "passive")
		)
		(pad "AB32" smd circle
			(at 5.25 8.215 270)
			(size 0.5 0.5)
			(layers "F.Cu" "F.Mask" "F.Paste")
			(net 23 "GND")
			(pinfunction "VSSA")
			(pintype "passive")
		)
		(pad "AB34" smd circle
			(at 6.25 8.215 270)
			(size 0.5 0.5)
			(layers "F.Cu" "F.Mask" "F.Paste")
			(net 23 "GND")
			(pinfunction "VSSA")
			(pintype "passive")
		)
		(pad "AB36" smd circle
			(at 7.25 8.215 270)
			(size 0.5 0.5)
			(layers "F.Cu" "F.Mask" "F.Paste")
			(net 23 "GND")
			(pinfunction "VSSA")
			(pintype "passive")
		)
		(pad "AB38" smd circle
			(at 8.25 8.215 270)
			(size 0.5 0.5)
			(layers "F.Cu" "F.Mask" "F.Paste")
			(net 23 "GND")
			(pinfunction "VSSA")
			(pintype "passive")
		)
		(pad "AB40" smd circle
			(at 9.25 8.215 270)
			(size 0.5 0.5)
			(layers "F.Cu" "F.Mask" "F.Paste")
			(net 23 "GND")
			(pinfunction "VSSA")
			(pintype "passive")
		)
		(pad "AB42" smd circle
			(at 10.25 8.215 270)
			(size 0.5 0.5)
			(layers "F.Cu" "F.Mask" "F.Paste")
			(net 74 "/X710-AT2 Misc/LAN_PWR_GOOD")
			(pinfunction "LAN_PWR_GOOD")
			(pintype "input")
		)
		(pad "AC1" smd circle
			(at -10.25 9.08 270)
			(size 0.5 0.5)
			(layers "F.Cu" "F.Mask" "F.Paste")
			(net 23 "GND")
			(pinfunction "VSSA")
			(pintype "passive")
		)
		(pad "AC3" smd circle
			(at -9.25 9.08 270)
			(size 0.5 0.5)
			(layers "F.Cu" "F.Mask" "F.Paste")
			(net 23 "GND")
			(pinfunction "VSSA")
			(pintype "passive")
		)
		(pad "AC5" smd circle
			(at -8.25 9.08 270)
			(size 0.5 0.5)
			(layers "F.Cu" "F.Mask" "F.Paste")
			(net 28 "/X710-AT2 PCIe/PCIe_{x4}_AC.TX0-")
			(pinfunction "PET_0_N")
			(pintype "output")
		)
		(pad "AC7" smd circle
			(at -7.25 9.08 270)
			(size 0.5 0.5)
			(layers "F.Cu" "F.Mask" "F.Paste")
			(net 23 "GND")
			(pinfunction "VSSA")
			(pintype "passive")
		)
		(pad "AC9" smd circle
			(at -6.25 9.08 270)
			(size 0.5 0.5)
			(layers "F.Cu" "F.Mask" "F.Paste")
			(net 23 "GND")
			(pinfunction "VSSA")
			(pintype "passive")
		)
		(pad "AC11" smd circle
			(at -5.25 9.08 270)
			(size 0.5 0.5)
			(layers "F.Cu" "F.Mask" "F.Paste")
			(net 23 "GND")
			(pinfunction "VSSA")
			(pintype "passive")
		)
		(pad "AC13" smd circle
			(at -4.25 9.08 270)
			(size 0.5 0.5)
			(layers "F.Cu" "F.Mask" "F.Paste")
			(net 23 "GND")
			(pinfunction "VSSA")
			(pintype "passive")
		)
		(pad "AC15" smd circle
			(at -3.25 9.08 270)
			(size 0.5 0.5)
			(layers "F.Cu" "F.Mask" "F.Paste")
			(net 23 "GND")
			(pinfunction "VSSA")
			(pintype "passive")
		)
		(pad "AC17" smd circle
			(at -2.25 9.08 270)
			(size 0.5 0.5)
			(layers "F.Cu" "F.Mask" "F.Paste")
			(net 23 "GND")
			(pinfunction "VSSA")
			(pintype "passive")
		)
		(pad "AC19" smd circle
			(at -1.25 9.08 270)
			(size 0.5 0.5)
			(layers "F.Cu" "F.Mask" "F.Paste")
			(net 23 "GND")
			(pinfunction "VSSA")
			(pintype "passive")
		)
		(pad "AC21" smd circle
			(at -0.25 9.08 270)
			(size 0.5 0.5)
			(layers "F.Cu" "F.Mask" "F.Paste")
			(net 23 "GND")
			(pinfunction "VSSA")
			(pintype "passive")
		)
		(pad "AC23" smd circle
			(at 0.75 9.08 270)
			(size 0.5 0.5)
			(layers "F.Cu" "F.Mask" "F.Paste")
			(net 23 "GND")
			(pinfunction "VSSA")
			(pintype "passive")
		)
		(pad "AC25" smd circle
			(at 1.75 9.08 270)
			(size 0.5 0.5)
			(layers "F.Cu" "F.Mask" "F.Paste")
			(net 23 "GND")
			(pinfunction "VSSA")
			(pintype "passive")
		)
		(pad "AC27" smd circle
			(at 2.75 9.08 270)
			(size 0.5 0.5)
			(layers "F.Cu" "F.Mask" "F.Paste")
			(net 23 "GND")
			(pinfunction "VSSA")
			(pintype "passive")
		)
		(pad "AC29" smd circle
			(at 3.75 9.08 270)
			(size 0.5 0.5)
			(layers "F.Cu" "F.Mask" "F.Paste")
			(net 23 "GND")
			(pinfunction "VSSA")
			(pintype "passive")
		)
		(pad "AC31" smd circle
			(at 4.75 9.08 270)
			(size 0.5 0.5)
			(layers "F.Cu" "F.Mask" "F.Paste")
			(net 579 "unconnected-(U14A-PET_5_P-PadAC31)")
			(pinfunction "PET_5_P")
			(pintype "output+no_connect")
		)
		(pad "AC33" smd circle
			(at 5.75 9.08 270)
			(size 0.5 0.5)
			(layers "F.Cu" "F.Mask" "F.Paste")
			(net 23 "GND")
			(pinfunction "VSSA")
			(pintype "passive")
		)
		(pad "AC35" smd circle
			(at 6.75 9.08 270)
			(size 0.5 0.5)
			(layers "F.Cu" "F.Mask" "F.Paste")
			(net 581 "unconnected-(U14A-PET_6_P-PadAC35)")
			(pinfunction "PET_6_P")
			(pintype "output+no_connect")
		)
		(pad "AC37" smd circle
			(at 7.75 9.08 270)
			(size 0.5 0.5)
			(layers "F.Cu" "F.Mask" "F.Paste")
			(net 23 "GND")
			(pinfunction "VSSA")
			(pintype "passive")
		)
		(pad "AC39" smd circle
			(at 8.75 9.08 270)
			(size 0.5 0.5)
			(layers "F.Cu" "F.Mask" "F.Paste")
			(net 571 "unconnected-(U14A-PET_7_P-PadAC39)")
			(pinfunction "PET_7_P")
			(pintype "output+no_connect")
		)
		(pad "AC41" smd circle
			(at 9.75 9.08 270)
			(size 0.5 0.5)
			(layers "F.Cu" "F.Mask" "F.Paste")
			(net 23 "GND")
			(pinfunction "VSSA")
			(pintype "passive")
		)
		(pad "AD2" smd circle
			(at -9.75 9.945 270)
			(size 0.5 0.5)
			(layers "F.Cu" "F.Mask" "F.Paste")
			(net 23 "GND")
			(pinfunction "VSSA")
			(pintype "passive")
		)
	)
)
